(kicad_pcb
	(version 20260206)
	(generator "pcbnew")
	(generator_version "10.0")
	(general
		(thickness 1.6)
		(legacy_teardrops no)
	)
	(paper "A4")
	(title_block
		(title "Bryce Canyon_IOM_IOC_16318-2_OCP.brd")
		(comment 1 "Bryce Canyon / footprints 1321-1328 of 1605")
	)
	(layers
		(0 "F.Cu" signal "TOP")
		(4 "In1.Cu" signal "L2GND")
		(6 "In2.Cu" signal "L3")
		(8 "In3.Cu" signal "L4VCC")
		(10 "In4.Cu" signal "L5VCC")
		(12 "In5.Cu" signal "L6")
		(14 "In6.Cu" signal "L7GND")
		(2 "B.Cu" signal "BOTTOM")
		(9 "F.Adhes" user "F.Adhesive")
		(11 "B.Adhes" user "B.Adhesive")
		(13 "F.Paste" user "Package Geometry/Pastemask Top")
		(15 "B.Paste" user "Package Geometry/Pastemask Bottom")
		(5 "F.SilkS" user "Ref Des/Silkscreen Top")
		(7 "B.SilkS" user "Ref Des/Silkscreen Bottom")
		(1 "F.Mask" user "Board Geometry/Soldermask Top")
		(3 "B.Mask" user "Board Geometry/Soldermask Bottom")
		(17 "Dwgs.User" user "User.Drawings")
		(19 "Cmts.User" user "User.Comments")
		(21 "Eco1.User" user "User.Eco1")
		(23 "Eco2.User" user "User.Eco2")
		(25 "Edge.Cuts" user "Board Geometry/Outline")
		(27 "Margin" user)
		(31 "F.CrtYd" user "Package Geometry/Place Bound Top")
		(29 "B.CrtYd" user "Package Geometry/Place Bound Bottom")
		(35 "F.Fab" user "Ref Des/Assembly Top")
		(33 "B.Fab" user "Ref Des/Assembly Bottom")
	)
	(footprint ""
		(layer "B.Cu")
		(at 52.2097 -160.8963 -90)
		(property "Reference" "C121"
			(at 0 0 90)
			(layer "B.SilkS")
			(hide yes)
			(effects
				(font
					(size 1.27 1.27)
				)
				(justify mirror)
			)
		)
		(property "Value" "SCD1U25V2KX-2-GP"
			(at -1.1811 -2.7051 270)
			(unlocked yes)
			(layer "B.Fab")
			(hide yes)
			(effects
				(font
					(size 1.016 1.016)
					(thickness 0.1524)
				)
				(justify mirror)
			)
		)
		(property "Device Type" "C402H22"
			(at -1.1811 -4.2291 270)
			(unlocked yes)
			(layer "B.Fab")
			(hide yes)
			(effects
				(font
					(size 1.016 1.016)
					(thickness 0.1524)
				)
				(justify mirror)
			)
		)
		(duplicate_pad_numbers_are_jumpers no)
		(fp_rect
			(start 0.4318 0.9525)
			(end -0.4318 -0.9525)
			(stroke
				(width 0)
				(type default)
			)
			(fill no)
			(layer "B.CrtYd")
		)
		(fp_rect
			(start 0.4318 0.9525)
			(end -0.4318 -0.9525)
			(stroke
				(width 0)
				(type default)
			)
			(fill no)
			(layer "B.Fab")
		)
		(pad "1" smd custom
			(at 0 -0.4445 90)
			(size 0.1524 0.1524)
			(layers "B.Cu" "B.Mask" "B.Paste")
			(net "ADC_P1V5")
			(options
				(clearance outline)
				(anchor circle)
			)
			(primitives
				(gr_poly
					(pts
						(arc
							(start 0.3048 0.2032)
							(mid 0.275042 0.275042)
							(end 0.2032 0.3048)
						)
						(arc
							(start -0.2032 0.3048)
							(mid -0.275042 0.275042)
							(end -0.3048 0.2032)
						)
						(arc
							(start -0.3048 -0.2032)
							(mid -0.275042 -0.275042)
							(end -0.2032 -0.3048)
						)
						(arc
							(start 0.2032 -0.3048)
							(mid 0.275042 -0.275042)
							(end 0.3048 -0.2032)
						)
					)
					(width 0)
					(fill yes)
				)
			)
		)
		(pad "2" smd custom
			(at 0 0.4445 90)
			(size 0.1524 0.1524)
			(layers "B.Cu" "B.Mask" "B.Paste")
			(net "GND")
			(options
				(clearance outline)
				(anchor circle)
			)
			(primitives
				(gr_poly
					(pts
						(arc
							(start 0.3048 0.2032)
							(mid 0.275042 0.275042)
							(end 0.2032 0.3048)
						)
						(arc
							(start -0.2032 0.3048)
							(mid -0.275042 0.275042)
							(end -0.3048 0.2032)
						)
						(arc
							(start -0.3048 -0.2032)
							(mid -0.275042 -0.275042)
							(end -0.2032 -0.3048)
						)
						(arc
							(start 0.2032 -0.3048)
							(mid 0.275042 -0.275042)
							(end 0.3048 -0.2032)
						)
					)
					(width 0)
					(fill yes)
				)
			)
		)
	)
	(footprint ""
		(layer "B.Cu")
		(at 10.20699 -141.008862 90)
		(property "Reference" "R254"
			(at 0 0 90)
			(layer "B.SilkS")
			(hide yes)
			(effects
				(font
					(size 1.27 1.27)
				)
				(justify mirror)
			)
		)
		(property "Value" "120R2F-GP"
			(at -0.064008 -3.993896 90)
			(unlocked yes)
			(layer "B.Fab")
			(hide yes)
			(effects
				(font
					(size 1.016 1.016)
					(thickness 0.1524)
				)
				(justify mirror)
			)
		)
		(property "Device Type" "R402H16"
			(at -0.064008 -5.517896 90)
			(unlocked yes)
			(layer "B.Fab")
			(hide yes)
			(effects
				(font
					(size 1.016 1.016)
					(thickness 0.1524)
				)
				(justify mirror)
			)
		)
		(duplicate_pad_numbers_are_jumpers no)
		(fp_line
			(start 0.508 -0.9398)
			(end 0.508 0.9398)
			(stroke
				(width 0.1524)
				(type default)
			)
			(layer "B.SilkS")
		)
		(fp_line
			(start -0.508 -0.9398)
			(end 0.508 -0.9398)
			(stroke
				(width 0.1524)
				(type default)
			)
			(layer "B.SilkS")
		)
		(fp_rect
			(start 0.508 0.9398)
			(end -0.508 -0.9398)
			(stroke
				(width 0)
				(type default)
			)
			(fill no)
			(layer "B.CrtYd")
		)
		(fp_rect
			(start 0.508 0.9398)
			(end -0.508 -0.9398)
			(stroke
				(width 0)
				(type default)
			)
			(fill no)
			(layer "B.Fab")
		)
		(pad "1" smd custom
			(at 0 -0.4445 270)
			(size 0.1397 0.1397)
			(layers "B.Cu" "B.Mask" "B.Paste")
			(net "GND")
			(options
				(clearance outline)
				(anchor circle)
			)
			(primitives
				(gr_poly
					(pts
						(arc
							(start -0.1778 0.2794)
							(mid -0.249642 0.249642)
							(end -0.2794 0.1778)
						)
						(arc
							(start -0.2794 -0.1778)
							(mid -0.249642 -0.249642)
							(end -0.1778 -0.2794)
						)
						(arc
							(start 0.1778 -0.2794)
							(mid 0.249642 -0.249642)
							(end 0.2794 -0.1778)
						)
						(arc
							(start 0.2794 0.1778)
							(mid 0.249642 0.249642)
							(end 0.1778 0.2794)
						)
					)
					(width 0)
					(fill yes)
				)
			)
		)
		(pad "2" smd custom
			(at 0 0.4445 270)
			(size 0.1397 0.1397)
			(layers "B.Cu" "B.Mask" "B.Paste")
			(net "MEMA_10")
			(options
				(clearance outline)
				(anchor circle)
			)
			(primitives
				(gr_poly
					(pts
						(arc
							(start -0.1778 0.2794)
							(mid -0.249642 0.249642)
							(end -0.2794 0.1778)
						)
						(arc
							(start -0.2794 -0.1778)
							(mid -0.249642 -0.249642)
							(end -0.1778 -0.2794)
						)
						(arc
							(start 0.1778 -0.2794)
							(mid 0.249642 -0.249642)
							(end 0.2794 -0.1778)
						)
						(arc
							(start 0.2794 0.1778)
							(mid 0.249642 0.249642)
							(end 0.1778 0.2794)
						)
					)
					(width 0)
					(fill yes)
				)
			)
		)
	)
	(footprint ""
		(layer "B.Cu")
		(at 200.3933 -58.7629 -90)
		(property "Reference" "C443"
			(at 0 0 90)
			(layer "B.SilkS")
			(hide yes)
			(effects
				(font
					(size 1.27 1.27)
				)
				(justify mirror)
			)
		)
		(property "Value" "SCD1U16V2KX-3GP"
			(at -1.1811 -2.7051 270)
			(unlocked yes)
			(layer "B.Fab")
			(hide yes)
			(effects
				(font
					(size 1.016 1.016)
					(thickness 0.1524)
				)
				(justify mirror)
			)
		)
		(property "Device Type" "C402H22"
			(at -1.1811 -4.2291 270)
			(unlocked yes)
			(layer "B.Fab")
			(hide yes)
			(effects
				(font
					(size 1.016 1.016)
					(thickness 0.1524)
				)
				(justify mirror)
			)
		)
		(duplicate_pad_numbers_are_jumpers no)
		(fp_rect
			(start 0.4318 0.9525)
			(end -0.4318 -0.9525)
			(stroke
				(width 0)
				(type default)
			)
			(fill no)
			(layer "B.CrtYd")
		)
		(fp_rect
			(start 0.4318 0.9525)
			(end -0.4318 -0.9525)
			(stroke
				(width 0)
				(type default)
			)
			(fill no)
			(layer "B.Fab")
		)
		(pad "1" smd custom
			(at 0 -0.4445 90)
			(size 0.1524 0.1524)
			(layers "B.Cu" "B.Mask" "B.Paste")
			(net "P1V8")
			(options
				(clearance outline)
				(anchor circle)
			)
			(primitives
				(gr_poly
					(pts
						(arc
							(start 0.3048 0.2032)
							(mid 0.275042 0.275042)
							(end 0.2032 0.3048)
						)
						(arc
							(start -0.2032 0.3048)
							(mid -0.275042 0.275042)
							(end -0.3048 0.2032)
						)
						(arc
							(start -0.3048 -0.2032)
							(mid -0.275042 -0.275042)
							(end -0.2032 -0.3048)
						)
						(arc
							(start 0.2032 -0.3048)
							(mid 0.275042 -0.275042)
							(end 0.3048 -0.2032)
						)
					)
					(width 0)
					(fill yes)
				)
			)
		)
		(pad "2" smd custom
			(at 0 0.4445 90)
			(size 0.1524 0.1524)
			(layers "B.Cu" "B.Mask" "B.Paste")
			(net "GND")
			(options
				(clearance outline)
				(anchor circle)
			)
			(primitives
				(gr_poly
					(pts
						(arc
							(start 0.3048 0.2032)
							(mid 0.275042 0.275042)
							(end 0.2032 0.3048)
						)
						(arc
							(start -0.2032 0.3048)
							(mid -0.275042 0.275042)
							(end -0.3048 0.2032)
						)
						(arc
							(start -0.3048 -0.2032)
							(mid -0.275042 -0.275042)
							(end -0.2032 -0.3048)
						)
						(arc
							(start 0.2032 -0.3048)
							(mid 0.275042 -0.275042)
							(end 0.3048 -0.2032)
						)
					)
					(width 0)
					(fill yes)
				)
			)
		)
	)
	(footprint ""
		(layer "B.Cu")
		(at 90.86088 -175.768 90)
		(property "Reference" "U12"
			(at 0 0 90)
			(layer "B.SilkS")
			(hide yes)
			(effects
				(font
					(size 1.27 1.27)
				)
				(justify mirror)
			)
		)
		(property "Value" "NX3L1G66GW-GP"
			(at 2.3368 -8.6868 90)
			(unlocked yes)
			(layer "B.Fab")
			(hide yes)
			(effects
				(font
					(size 1.016 1.016)
					(thickness 0.1524)
				)
				(justify mirror)
			)
		)
		(property "Device Type" "SC70-5H44"
			(at 2.3114 -10.414 90)
			(unlocked yes)
			(layer "B.Fab")
			(hide yes)
			(effects
				(font
					(size 1.016 1.016)
					(thickness 0.1524)
				)
				(justify mirror)
			)
		)
		(duplicate_pad_numbers_are_jumpers no)
		(fp_line
			(start -0.6604 -1.8034)
			(end -1.3843 -1.8034)
			(stroke
				(width 0.3302)
				(type default)
			)
			(layer "B.SilkS")
		)
		(fp_line
			(start -1.3843 -1.8034)
			(end -1.3843 -1.1176)
			(stroke
				(width 0.3302)
				(type default)
			)
			(layer "B.SilkS")
		)
		(fp_line
			(start 1.27 -1.7018)
			(end -1.27 -1.7018)
			(stroke
				(width 0.1524)
				(type default)
			)
			(layer "B.SilkS")
		)
		(fp_line
			(start -1.27 -1.7018)
			(end -1.27 1.7018)
			(stroke
				(width 0.1524)
				(type default)
			)
			(layer "B.SilkS")
		)
		(fp_line
			(start 1.27 1.7018)
			(end 1.27 -1.7018)
			(stroke
				(width 0.1524)
				(type default)
			)
			(layer "B.SilkS")
		)
		(fp_line
			(start -1.27 1.7018)
			(end 1.27 1.7018)
			(stroke
				(width 0.1524)
				(type default)
			)
			(layer "B.SilkS")
		)
		(fp_rect
			(start 1.524 1.9558)
			(end -1.524 -1.9558)
			(stroke
				(width 0)
				(type default)
			)
			(fill no)
			(layer "B.CrtYd")
		)
		(fp_poly
			(pts
				(xy 1.524 -1.9558) (xy -1.524 -1.9558) (xy -1.524 1.9558) (xy 1.524 1.9558)
			)
			(stroke
				(width 0)
				(type default)
			)
			(fill no)
			(layer "B.Fab")
		)
		(pad "1" smd rect
			(at -0.65024 -0.8255 270)
			(size 0.4064 1.2192)
			(layers "B.Cu" "B.Mask" "B.Paste")
			(net "I2C_BMC_COMP_SCL_R")
		)
		(pad "2" smd rect
			(at 0 -0.8255 270)
			(size 0.4064 1.2192)
			(layers "B.Cu" "B.Mask" "B.Paste")
			(net "I2C_BMC_COMP_SCL_OUT")
		)
		(pad "3" smd rect
			(at 0.65024 -0.8255 270)
			(size 0.4064 1.2192)
			(layers "B.Cu" "B.Mask" "B.Paste")
			(net "GND")
		)
		(pad "4" smd rect
			(at 0.65024 0.8255 270)
			(size 0.4064 1.2192)
			(layers "B.Cu" "B.Mask" "B.Paste")
			(net "COMP_PWR_EN")
		)
		(pad "5" smd rect
			(at -0.65024 0.8255 270)
			(size 0.4064 1.2192)
			(layers "B.Cu" "B.Mask" "B.Paste")
			(net "P3V3_STBY")
		)
	)
	(footprint ""
		(layer "B.Cu")
		(at 200.3933 -59.63158 -90)
		(property "Reference" "C440"
			(at 0 0 90)
			(layer "B.SilkS")
			(hide yes)
			(effects
				(font
					(size 1.27 1.27)
				)
				(justify mirror)
			)
		)
		(property "Value" "SCD1U16V2KX-3GP"
			(at -1.1811 -2.7051 270)
			(unlocked yes)
			(layer "B.Fab")
			(hide yes)
			(effects
				(font
					(size 1.016 1.016)
					(thickness 0.1524)
				)
				(justify mirror)
			)
		)
		(property "Device Type" "C402H22"
			(at -1.1811 -4.2291 270)
			(unlocked yes)
			(layer "B.Fab")
			(hide yes)
			(effects
				(font
					(size 1.016 1.016)
					(thickness 0.1524)
				)
				(justify mirror)
			)
		)
		(duplicate_pad_numbers_are_jumpers no)
		(fp_rect
			(start 0.4318 0.9525)
			(end -0.4318 -0.9525)
			(stroke
				(width 0)
				(type default)
			)
			(fill no)
			(layer "B.CrtYd")
		)
		(fp_rect
			(start 0.4318 0.9525)
			(end -0.4318 -0.9525)
			(stroke
				(width 0)
				(type default)
			)
			(fill no)
			(layer "B.Fab")
		)
		(pad "1" smd custom
			(at 0 -0.4445 90)
			(size 0.1524 0.1524)
			(layers "B.Cu" "B.Mask" "B.Paste")
			(net "P1V8")
			(options
				(clearance outline)
				(anchor circle)
			)
			(primitives
				(gr_poly
					(pts
						(arc
							(start 0.3048 0.2032)
							(mid 0.275042 0.275042)
							(end 0.2032 0.3048)
						)
						(arc
							(start -0.2032 0.3048)
							(mid -0.275042 0.275042)
							(end -0.3048 0.2032)
						)
						(arc
							(start -0.3048 -0.2032)
							(mid -0.275042 -0.275042)
							(end -0.2032 -0.3048)
						)
						(arc
							(start 0.2032 -0.3048)
							(mid 0.275042 -0.275042)
							(end 0.3048 -0.2032)
						)
					)
					(width 0)
					(fill yes)
				)
			)
		)
		(pad "2" smd custom
			(at 0 0.4445 90)
			(size 0.1524 0.1524)
			(layers "B.Cu" "B.Mask" "B.Paste")
			(net "GND")
			(options
				(clearance outline)
				(anchor circle)
			)
			(primitives
				(gr_poly
					(pts
						(arc
							(start 0.3048 0.2032)
							(mid 0.275042 0.275042)
							(end 0.2032 0.3048)
						)
						(arc
							(start -0.2032 0.3048)
							(mid -0.275042 0.275042)
							(end -0.3048 0.2032)
						)
						(arc
							(start -0.3048 -0.2032)
							(mid -0.275042 -0.275042)
							(end -0.2032 -0.3048)
						)
						(arc
							(start 0.2032 -0.3048)
							(mid 0.275042 -0.275042)
							(end 0.3048 -0.2032)
						)
					)
					(width 0)
					(fill yes)
				)
			)
		)
	)
	(footprint ""
		(layer "B.Cu")
		(at 31.3944 -123.8631 -90)
		(property "Reference" "U104"
			(at 0 0 90)
			(layer "B.SilkS")
			(hide yes)
			(effects
				(font
					(size 1.27 1.27)
				)
				(justify mirror)
			)
		)
		(property "Value" "SNLVC1G126DCKR-GP"
			(at 2.3368 -8.6868 270)
			(unlocked yes)
			(layer "B.Fab")
			(hide yes)
			(effects
				(font
					(size 1.016 1.016)
					(thickness 0.1524)
				)
				(justify mirror)
			)
		)
		(property "Device Type" "SC70-5H44"
			(at 2.3114 -10.414 270)
			(unlocked yes)
			(layer "B.Fab")
			(hide yes)
			(effects
				(font
					(size 1.016 1.016)
					(thickness 0.1524)
				)
				(justify mirror)
			)
		)
		(duplicate_pad_numbers_are_jumpers no)
		(fp_line
			(start -1.27 1.7018)
			(end 1.27 1.7018)
			(stroke
				(width 0.1524)
				(type default)
			)
			(layer "B.SilkS")
		)
		(fp_line
			(start 1.27 1.7018)
			(end 1.27 -1.7018)
			(stroke
				(width 0.1524)
				(type default)
			)
			(layer "B.SilkS")
		)
		(fp_line
			(start -1.27 -1.7018)
			(end -1.27 1.7018)
			(stroke
				(width 0.1524)
				(type default)
			)
			(layer "B.SilkS")
		)
		(fp_line
			(start 1.27 -1.7018)
			(end -1.27 -1.7018)
			(stroke
				(width 0.1524)
				(type default)
			)
			(layer "B.SilkS")
		)
		(fp_line
			(start -1.3843 -1.8034)
			(end -1.3843 -1.1176)
			(stroke
				(width 0.3302)
				(type default)
			)
			(layer "B.SilkS")
		)
		(fp_line
			(start -0.6604 -1.8034)
			(end -1.3843 -1.8034)
			(stroke
				(width 0.3302)
				(type default)
			)
			(layer "B.SilkS")
		)
		(fp_rect
			(start 1.524 1.9558)
			(end -1.524 -1.9558)
			(stroke
				(width 0)
				(type default)
			)
			(fill no)
			(layer "B.CrtYd")
		)
		(fp_poly
			(pts
				(xy 1.524 -1.9558) (xy -1.524 -1.9558) (xy -1.524 1.9558) (xy 1.524 1.9558)
			)
			(stroke
				(width 0)
				(type default)
			)
			(fill no)
			(layer "B.Fab")
		)
		(pad "1" smd rect
			(at -0.65024 -0.8255 90)
			(size 0.4064 1.2192)
			(layers "B.Cu" "B.Mask" "B.Paste")
			(net "U104_EN")
		)
		(pad "2" smd rect
			(at 0 -0.8255 90)
			(size 0.4064 1.2192)
			(layers "B.Cu" "B.Mask" "B.Paste")
			(net "SYS_RESET_N_OUT")
		)
		(pad "3" smd rect
			(at 0.65024 -0.8255 90)
			(size 0.4064 1.2192)
			(layers "B.Cu" "B.Mask" "B.Paste")
			(net "GND")
		)
		(pad "4" smd rect
			(at 0.65024 0.8255 90)
			(size 0.4064 1.2192)
			(layers "B.Cu" "B.Mask" "B.Paste")
			(net "SYS_RESET_N")
		)
		(pad "5" smd rect
			(at -0.65024 0.8255 90)
			(size 0.4064 1.2192)
			(layers "B.Cu" "B.Mask" "B.Paste")
			(net "P3V3_STBY")
		)
	)
	(footprint ""
		(layer "B.Cu")
		(at 182.43804 -74.917554)
		(property "Reference" "TP110"
			(at 0 0 0)
			(layer "B.SilkS")
			(hide yes)
			(effects
				(font
					(size 1.27 1.27)
				)
				(justify mirror)
			)
		)
		(property "Value" "TPAD28-2-GP"
			(at 0.0127 -1.6637 0)
			(unlocked yes)
			(layer "B.Fab")
			(hide yes)
			(effects
				(font
					(size 1.016 1.016)
					(thickness 0.1524)
				)
				(justify mirror)
			)
		)
		(property "Device Type" "TPAD28"
			(at 0.0127 -3.1877 0)
			(unlocked yes)
			(layer "B.Fab")
			(hide yes)
			(effects
				(font
					(size 1.016 1.016)
					(thickness 0.1524)
				)
				(justify mirror)
			)
		)
		(duplicate_pad_numbers_are_jumpers no)
		(fp_poly
			(pts
				(arc
					(start 0.3556 0)
					(mid -0.3556 0)
					(end 0.3556 0)
				)
			)
			(stroke
				(width 0)
				(type default)
			)
			(fill no)
			(layer "B.CrtYd")
		)
		(fp_poly
			(pts
				(arc
					(start 0.6096 0)
					(mid -0.6096 0)
					(end 0.6096 0)
				)
			)
			(stroke
				(width 0)
				(type default)
			)
			(fill no)
			(layer "B.Fab")
		)
		(pad "1" smd circle
			(at 0 0 180)
			(size 0.7112 0.7112)
			(layers "B.Cu" "B.Mask" "B.Paste")
			(net "IOC_GPIO_25")
		)
	)
	(footprint ""
		(layer "B.Cu")
		(at 197.5612 -52.451 -90)
		(property "Reference" "C349"
			(at 0 0 90)
			(layer "B.SilkS")
			(hide yes)
			(effects
				(font
					(size 1.27 1.27)
				)
				(justify mirror)
			)
		)
		(property "Value" "SCD1U6D3V1KX-GP"
			(at 2.8321 -1.7399 270)
			(unlocked yes)
			(layer "B.Fab")
			(hide yes)
			(effects
				(font
					(size 1.016 1.016)
					(thickness 0.1524)
				)
				(justify mirror)
			)
		)
		(property "Device Type" "C0201H13"
			(at 2.8321 -3.2639 270)
			(unlocked yes)
			(layer "B.Fab")
			(hide yes)
			(effects
				(font
					(size 1.016 1.016)
					(thickness 0.1524)
				)
				(justify mirror)
			)
		)
		(duplicate_pad_numbers_are_jumpers no)
		(fp_rect
			(start 0.2794 0.6477)
			(end -0.2794 -0.6477)
			(stroke
				(width 0)
				(type default)
			)
			(fill no)
			(layer "B.CrtYd")
		)
		(fp_rect
			(start 0.2794 0.6477)
			(end -0.2794 -0.6477)
			(stroke
				(width 0)
				(type default)
			)
			(fill no)
			(layer "B.Fab")
		)
		(pad "1" smd custom
			(at 0 -0.2794 90)
			(size 0.0762 0.0762)
			(layers "B.Cu" "B.Mask" "B.Paste")
			(net "VDDA_SAS_REF_CLK")
			(options
				(clearance outline)
				(anchor circle)
			)
			(primitives
				(gr_poly
					(pts
						(arc
							(start 0.1524 0.127)
							(mid 0.137521 0.162921)
							(end 0.1016 0.1778)
						)
						(arc
							(start -0.1016 0.1778)
							(mid -0.137521 0.162921)
							(end -0.1524 0.127)
						)
						(arc
							(start -0.1524 -0.127)
							(mid -0.137521 -0.162921)
							(end -0.1016 -0.1778)
						)
						(arc
							(start 0.1016 -0.1778)
							(mid 0.137521 -0.162921)
							(end 0.1524 -0.127)
						)
					)
					(width 0)
					(fill yes)
				)
			)
		)
		(pad "2" smd custom
			(at 0 0.2794 90)
			(size 0.0762 0.0762)
			(layers "B.Cu" "B.Mask" "B.Paste")
			(net "GND")
			(options
				(clearance outline)
				(anchor circle)
			)
			(primitives
				(gr_poly
					(pts
						(arc
							(start 0.1524 0.127)
							(mid 0.137521 0.162921)
							(end 0.1016 0.1778)
						)
						(arc
							(start -0.1016 0.1778)
							(mid -0.137521 0.162921)
							(end -0.1524 0.127)
						)
						(arc
							(start -0.1524 -0.127)
							(mid -0.137521 -0.162921)
							(end -0.1016 -0.1778)
						)
						(arc
							(start 0.1016 -0.1778)
							(mid 0.137521 -0.162921)
							(end 0.1524 -0.127)
						)
					)
					(width 0)
					(fill yes)
				)
			)
		)
	)
)
